# T6G (Grand Teton) — schematic netlist excerpt (pin names and nets, part order shuffled) for the footprints in the layout excerpt that follows; sources: Cadence DE-HDL packaged netlist, KiCad conversion of 04192023_DAF0TMB3IC0_F0TG_MB_C_brd_V02_OCP.brd

PJ38  SCONN21_9193031121LF  SCONN21_91930-31121LF IO  pkg CON_F21S2H2D2S_P1W4-22_LDH  page 267
  \1\  = P12V_PSU
  \2\  = P12V_HSC_SENSE1_P
  \3\  = P12V_HSC_SENSE1_N
  \4\  = P12V_HSC_SENSE2_P
  \5\  = P12V_HSC_SENSE2_N
  \6\  = P12V_HSC_ADC_N
  \7\  = P12V_HSC_ADC_P
  \8\  = P12V_HSC_GATE1
  \9\  = P12V_HSC_GATE2
  \10\  = P12V_AUX
  \11\  = GND
  \12\  = P3V3_AUX
  \13\  = IRQ_HSC_FAULT_N
  \14\  = HSC_EN
  \15\  = MB0_P12V_STBY_PWRGD
  \16\  = HSC_CSOUT
  \17\  = HSC_TYPE_ADC
  \18\  = SMB_SML1_PMBUS_HSC_R1_SCL
  \19\  = SMB_SML1_PMBUS_HSC_R1_SDA
  \20\  = IRQ_SML1_PMBUS_ALERT_N
  \21\  = GND
  G1  = GND
  G2  = GND

(kicad_pcb
	(version 20260206)
	(generator "pcbnew")
	(generator_version "10.0")
	(general
		(thickness 1.6)
		(legacy_teardrops no)
	)
	(paper "A4")
	(title_block
		(title "04192023_DAF0TMB3IC0_F0TG_MB_C_brd_V02_OCP.brd")
		(comment 1 "Grand Teton / footprint 390 of 8354 (PJ38), pads 1-25 of 25")
	)
	(layers
		(0 "F.Cu" signal "TOP")
		(4 "In1.Cu" signal "GND")
		(6 "In2.Cu" signal "IN1")
		(8 "In3.Cu" signal "GND1")
		(10 "In4.Cu" signal "IN2")
		(12 "In5.Cu" signal "GND2")
		(14 "In6.Cu" signal "IN3")
		(16 "In7.Cu" signal "GND3")
		(18 "In8.Cu" signal "VCC")
		(20 "In9.Cu" signal "VCC1")
		(22 "In10.Cu" signal "GND4")
		(24 "In11.Cu" signal "IN4")
		(26 "In12.Cu" signal "GND5")
		(28 "In13.Cu" signal "IN5")
		(30 "In14.Cu" signal "GND6")
		(32 "In15.Cu" signal "IN6")
		(34 "In16.Cu" signal "GND7")
		(2 "B.Cu" signal "BOTTOM")
		(9 "F.Adhes" user "F.Adhesive")
		(11 "B.Adhes" user "B.Adhesive")
		(13 "F.Paste" user "Package Geometry/Pastemask Top")
		(15 "B.Paste" user "Package Geometry/Pastemask Bottom")
		(5 "F.SilkS" user "Ref Des/Silkscreen Top")
		(7 "B.SilkS" user "Ref Des/Silkscreen Bottom")
		(1 "F.Mask" user "Board Geometry/Soldermask Top")
		(3 "B.Mask" user "Board Geometry/Soldermask Bottom")
		(17 "Dwgs.User" user "User.Drawings")
		(19 "Cmts.User" user "User.Comments")
		(21 "Eco1.User" user "User.Eco1")
		(23 "Eco2.User" user "User.Eco2")
		(25 "Edge.Cuts" user "Board Geometry/Outline")
		(27 "Margin" user)
		(31 "F.CrtYd" user "Package Geometry/Place Bound Top")
		(29 "B.CrtYd" user "Package Geometry/Place Bound Bottom")
		(35 "F.Fab" user "Ref Des/Assembly Top")
		(33 "B.Fab" user "Ref Des/Assembly Bottom")
	)
	(footprint ""
		(layer "F.Cu")
		(at 195.88988 -383.160524 180)
		(property "Reference" "PJ38"
			(at 4.616196 4.675886 90)
			(unlocked yes)
			(layer "F.SilkS")
			(effects
				(font
					(size 0.7874 0.5842)
					(thickness 0.1524)
				)
				(justify left)
			)
		)
		(property "Value" ""
			(at 0 0 180)
			(layer "F.Fab")
			(effects
				(font
					(size 1.27 1.27)
				)
			)
		)
		(duplicate_pad_numbers_are_jumpers no)
		(pad "" np_thru_hole circle
			(at 1.100074 -5.5245 90)
			(size 0.762 0.762)
			(drill 0.762)
			(layers "*.Cu" "*.Mask")
			(clearance 0.381)
			(thermal_gap 0.381)
		)
		(pad "" np_thru_hole circle
			(at 1.100074 5.5245 90)
			(size 0.762 0.762)
			(drill 0.762)
			(layers "*.Cu" "*.Mask")
			(clearance 0.381)
			(thermal_gap 0.381)
		)
		(pad "1" smd rect
			(at -2.109978 -4.99999 270)
			(size 0.6096 1.651)
			(layers "F.Cu" "F.Mask" "F.Paste")
			(net "P12V_PSU")
		)
		(pad "2" smd rect
			(at -2.109978 -3.999992 270)
			(size 0.6096 1.651)
			(layers "F.Cu" "F.Mask" "F.Paste")
			(net "P12V_HSC_SENSE1_P")
		)
		(pad "3" smd rect
			(at -2.109978 -2.999994 270)
			(size 0.6096 1.651)
			(layers "F.Cu" "F.Mask" "F.Paste")
			(net "P12V_HSC_SENSE1_N")
		)
		(pad "4" smd rect
			(at -2.109978 -1.999996 270)
			(size 0.6096 1.651)
			(layers "F.Cu" "F.Mask" "F.Paste")
			(net "P12V_HSC_SENSE2_P")
		)
		(pad "5" smd rect
			(at -2.109978 -0.999998 270)
			(size 0.6096 1.651)
			(layers "F.Cu" "F.Mask" "F.Paste")
			(net "P12V_HSC_SENSE2_N")
		)
		(pad "6" smd rect
			(at -2.109978 0 270)
			(size 0.6096 1.651)
			(layers "F.Cu" "F.Mask" "F.Paste")
			(net "P12V_HSC_ADC_N")
		)
		(pad "7" smd rect
			(at -2.109978 0.999998 270)
			(size 0.6096 1.651)
			(layers "F.Cu" "F.Mask" "F.Paste")
			(net "P12V_HSC_ADC_P")
		)
		(pad "8" smd rect
			(at -2.109978 1.999996 270)
			(size 0.6096 1.651)
			(layers "F.Cu" "F.Mask" "F.Paste")
			(net "P12V_HSC_GATE1")
		)
		(pad "9" smd rect
			(at -2.109978 2.999994 270)
			(size 0.6096 1.651)
			(layers "F.Cu" "F.Mask" "F.Paste")
			(net "P12V_HSC_GATE2")
		)
		(pad "10" smd rect
			(at -2.109978 3.999992 270)
			(size 0.6096 1.651)
			(layers "F.Cu" "F.Mask" "F.Paste")
			(net "P12V_AUX")
		)
		(pad "11" smd rect
			(at -2.109978 4.99999 270)
			(size 0.6096 1.651)
			(layers "F.Cu" "F.Mask" "F.Paste")
			(net "GND")
		)
		(pad "12" smd rect
			(at 2.109978 -4.500118 90)
			(size 0.6096 1.651)
			(layers "F.Cu" "F.Mask" "F.Paste")
			(net "P3V3_AUX")
		)
		(pad "13" smd rect
			(at 2.109978 -3.50012 90)
			(size 0.6096 1.651)
			(layers "F.Cu" "F.Mask" "F.Paste")
			(net "IRQ_HSC_FAULT_N")
		)
		(pad "14" smd rect
			(at 2.109978 -2.500122 90)
			(size 0.6096 1.651)
			(layers "F.Cu" "F.Mask" "F.Paste")
			(net "HSC_EN")
		)
		(pad "15" smd rect
			(at 2.109978 -1.500124 90)
			(size 0.6096 1.651)
			(layers "F.Cu" "F.Mask" "F.Paste")
			(net "MB0_P12V_STBY_PWRGD")
		)
		(pad "16" smd rect
			(at 2.109978 -0.499872 90)
			(size 0.6096 1.651)
			(layers "F.Cu" "F.Mask" "F.Paste")
			(net "HSC_CSOUT")
		)
		(pad "17" smd rect
			(at 2.109978 0.499872 90)
			(size 0.6096 1.651)
			(layers "F.Cu" "F.Mask" "F.Paste")
			(net "HSC_TYPE_ADC")
		)
		(pad "18" smd rect
			(at 2.109978 1.500124 90)
			(size 0.6096 1.651)
			(layers "F.Cu" "F.Mask" "F.Paste")
			(net "SMB_SML1_PMBUS_HSC_R1_SCL")
		)
		(pad "19" smd rect
			(at 2.109978 2.500122 90)
			(size 0.6096 1.651)
			(layers "F.Cu" "F.Mask" "F.Paste")
			(net "SMB_SML1_PMBUS_HSC_R1_SDA")
		)
		(pad "20" smd rect
			(at 2.109978 3.50012 90)
			(size 0.6096 1.651)
			(layers "F.Cu" "F.Mask" "F.Paste")
			(net "IRQ_SML1_PMBUS_ALERT_N")
		)
		(pad "21" smd rect
			(at 2.109978 4.500118 90)
			(size 0.6096 1.651)
			(layers "F.Cu" "F.Mask" "F.Paste")
			(net "GND")
		)
		(pad "G1" smd circle
			(at 0 -6.720078 90)
			(size 0 0)
			(layers "F.Cu" "F.Mask" "F.Paste")
			(net "GND")
		)
		(pad "G2" smd circle
			(at 0 6.720078 90)
			(size 0 0)
			(layers "F.Cu" "F.Mask" "F.Paste")
			(net "GND")
		)
	)
)
